# BASEBOARD_FAB2 (Tioga Pass) — schematic netlist excerpt (pin names and nets, part order shuffled) for the footprints in the layout excerpt that follows; sources: Cadence DE-HDL packaged netlist, KiCad conversion of Wiwynn_Tioga_Pass_MB.brd

R8W12  RES  0.0 5% CHIP  pkg 0402  page 245 : A = JTAG_RISER_TRST ; B = JTAG_BMC_TRST_N
R4L4  RES  120.0 1% CHIP  pkg 0603  page 220 : A = PVDDQ_DEF ; B = GND
C8C3  CAP  10UF 6.3V 20% X6S  pkg 0603  page 130 : A = P3V3_STBY ; B = GND

(kicad_pcb
	(version 20260206)
	(generator "pcbnew")
	(generator_version "10.0")
	(general
		(thickness 1.6)
		(legacy_teardrops no)
	)
	(paper "A4")
	(title_block
		(title "Wiwynn_Tioga_Pass_MB.brd")
		(comment 1 "Tioga Pass / footprints 2949-2951 of 4770")
	)
	(layers
		(0 "F.Cu" signal "TOP")
		(4 "In1.Cu" signal "L2GND")
		(6 "In2.Cu" signal "L3")
		(8 "In3.Cu" signal "L4GND")
		(10 "In4.Cu" signal "L5")
		(12 "In5.Cu" signal "L6GND")
		(14 "In6.Cu" signal "L7VCC")
		(16 "In7.Cu" signal "L8VCC")
		(18 "In8.Cu" signal "L9GND")
		(20 "In9.Cu" signal "L10")
		(22 "In10.Cu" signal "L11GND")
		(24 "In11.Cu" signal "L12")
		(26 "In12.Cu" signal "L13GND")
		(2 "B.Cu" signal "BOTTOM")
		(9 "F.Adhes" user "F.Adhesive")
		(11 "B.Adhes" user "B.Adhesive")
		(13 "F.Paste" user "Package Geometry/Pastemask Top")
		(15 "B.Paste" user "Package Geometry/Pastemask Bottom")
		(5 "F.SilkS" user "Ref Des/Silkscreen Top")
		(7 "B.SilkS" user "Ref Des/Silkscreen Bottom")
		(1 "F.Mask" user "Board Geometry/Soldermask Top")
		(3 "B.Mask" user "Board Geometry/Soldermask Bottom")
		(17 "Dwgs.User" user "User.Drawings")
		(19 "Cmts.User" user "User.Comments")
		(21 "Eco1.User" user "User.Eco1")
		(23 "Eco2.User" user "User.Eco2")
		(25 "Edge.Cuts" user "Board Geometry/Outline")
		(27 "Margin" user)
		(31 "F.CrtYd" user "Package Geometry/Place Bound Top")
		(29 "B.CrtYd" user "Package Geometry/Place Bound Bottom")
		(35 "F.Fab" user "Ref Des/Assembly Top")
		(33 "B.Fab" user "Ref Des/Assembly Bottom")
	)
	(footprint ""
		(layer "B.Cu")
		(at 358.3432 -4.2418 180)
		(property "Reference" "R8W12"
			(at 0.8382 -0.67818 180)
			(unlocked yes)
			(layer "B.SilkS")
			(effects
				(font
					(size 0.4064 0.254)
					(thickness 0.1524)
				)
				(justify left mirror)
			)
		)
		(property "Value" ""
			(at 0 0 0)
			(layer "B.Fab")
			(effects
				(font
					(size 1.27 1.27)
				)
				(justify mirror)
			)
		)
		(duplicate_pad_numbers_are_jumpers no)
		(fp_poly
			(pts
				(xy 0.2794 -0.1016) (xy -0.2794 -0.1016) (xy -0.2794 0.9906) (xy 0.2794 0.9906)
			)
			(stroke
				(width 0)
				(type default)
			)
			(fill no)
			(layer "B.CrtYd")
		)
		(fp_line
			(start 0.2794 0.9906)
			(end -0.2794 0.9906)
			(stroke
				(width 0.1)
				(type default)
			)
			(layer "B.Fab")
		)
		(fp_line
			(start 0.2794 -0.1016)
			(end 0.2794 0.9906)
			(stroke
				(width 0.1)
				(type default)
			)
			(layer "B.Fab")
		)
		(fp_line
			(start -0.2794 0.9906)
			(end -0.2794 -0.1016)
			(stroke
				(width 0.1)
				(type default)
			)
			(layer "B.Fab")
		)
		(fp_line
			(start -0.2794 -0.1016)
			(end 0.2794 -0.1016)
			(stroke
				(width 0.1)
				(type default)
			)
			(layer "B.Fab")
		)
		(pad "1" smd rect
			(at 0 0)
			(size 0.508 0.508)
			(layers "B.Cu" "B.Mask" "B.Paste")
			(net "JTAG_RISER_TRST")
		)
		(pad "2" smd rect
			(at 0 0.889)
			(size 0.508 0.508)
			(layers "B.Cu" "B.Mask" "B.Paste")
			(net "JTAG_BMC_TRST_N")
		)
		(zone
			(layer "B.Cu")
			(hatch none 0.5)
			(connect_pads
				(clearance 0)
			)
			(min_thickness 0.25)
			(keepout
				(tracks not_allowed)
				(vias allowed)
				(pads allowed)
				(copperpour not_allowed)
				(footprints allowed)
			)
			(placement
				(enabled no)
				(sheetname "")
			)
			(fill
				(thermal_gap 0.5)
				(thermal_bridge_width 0.5)
				(island_removal_mode 0)
			)
			(polygon
				(pts
					(xy 358.0892 -4.8768) (xy 358.5972 -4.8768) (xy 358.5972 -4.4958) (xy 358.0892 -4.4958)
				)
			)
		)
		(zone
			(layer "B.Cu")
			(hatch none 0.5)
			(connect_pads
				(clearance 0)
			)
			(min_thickness 0.25)
			(keepout
				(tracks allowed)
				(vias not_allowed)
				(pads allowed)
				(copperpour not_allowed)
				(footprints allowed)
			)
			(placement
				(enabled no)
				(sheetname "")
			)
			(fill
				(thermal_gap 0.5)
				(thermal_bridge_width 0.5)
				(island_removal_mode 0)
			)
			(polygon
				(pts
					(xy 358.0892 -4.4958) (xy 358.5972 -4.4958) (xy 358.5972 -4.8768) (xy 358.0892 -4.8768)
				)
			)
		)
	)
	(footprint ""
		(layer "B.Cu")
		(at 406.654 -94.474792 90)
		(property "Reference" "C8C3"
			(at 0 0 90)
			(layer "B.SilkS")
			(hide yes)
			(effects
				(font
					(size 1.27 1.27)
				)
				(justify mirror)
			)
		)
		(property "Value" ""
			(at 0 0 90)
			(layer "B.Fab")
			(effects
				(font
					(size 1.27 1.27)
				)
				(justify mirror)
			)
		)
		(duplicate_pad_numbers_are_jumpers no)
		(fp_poly
			(pts
				(xy 0.4953 -0.2032) (xy -0.4953 -0.2032) (xy -0.4953 1.6002) (xy 0.4953 1.6002)
			)
			(stroke
				(width 0)
				(type default)
			)
			(fill no)
			(layer "B.CrtYd")
		)
		(fp_line
			(start 0.4953 -0.2032)
			(end -0.4953 -0.2032)
			(stroke
				(width 0.1)
				(type default)
			)
			(layer "B.Fab")
		)
		(fp_line
			(start -0.4953 -0.2032)
			(end -0.4953 1.6002)
			(stroke
				(width 0.1)
				(type default)
			)
			(layer "B.Fab")
		)
		(fp_line
			(start 0.4953 1.6002)
			(end 0.4953 -0.2032)
			(stroke
				(width 0.1)
				(type default)
			)
			(layer "B.Fab")
		)
		(fp_line
			(start -0.4953 1.6002)
			(end 0.4953 1.6002)
			(stroke
				(width 0.1)
				(type default)
			)
			(layer "B.Fab")
		)
		(pad "1" smd rect
			(at 0 0 270)
			(size 0.762 0.889)
			(layers "B.Cu" "B.Mask" "B.Paste")
			(net "P3V3_STBY")
		)
		(pad "2" smd rect
			(at 0 1.397 270)
			(size 0.762 0.889)
			(layers "B.Cu" "B.Mask" "B.Paste")
			(net "GND")
		)
		(zone
			(layer "B.Cu")
			(hatch none 0.5)
			(connect_pads
				(clearance 0)
			)
			(min_thickness 0.25)
			(keepout
				(tracks not_allowed)
				(vias allowed)
				(pads allowed)
				(copperpour not_allowed)
				(footprints allowed)
			)
			(placement
				(enabled no)
				(sheetname "")
			)
			(fill
				(thermal_gap 0.5)
				(thermal_bridge_width 0.5)
				(island_removal_mode 0)
			)
			(polygon
				(pts
					(xy 407.0985 -94.855792) (xy 407.0985 -94.093792) (xy 407.6065 -94.093792) (xy 407.6065 -94.855792)
				)
			)
		)
	)
	(footprint ""
		(layer "B.Cu")
		(at 331.343 -155.829 180)
		(property "Reference" "R4L4"
			(at 0 0 0)
			(layer "B.SilkS")
			(hide yes)
			(effects
				(font
					(size 1.27 1.27)
				)
				(justify mirror)
			)
		)
		(property "Value" ""
			(at 0 0 0)
			(layer "B.Fab")
			(effects
				(font
					(size 1.27 1.27)
				)
				(justify mirror)
			)
		)
		(duplicate_pad_numbers_are_jumpers no)
		(fp_rect
			(start -0.4953 -0.2032)
			(end 0.4953 1.6002)
			(stroke
				(width 0)
				(type default)
			)
			(fill no)
			(layer "B.CrtYd")
		)
		(fp_line
			(start 0.4953 1.6002)
			(end 0.4953 -0.2032)
			(stroke
				(width 0.1)
				(type default)
			)
			(layer "B.Fab")
		)
		(fp_line
			(start 0.4953 -0.2032)
			(end -0.4953 -0.2032)
			(stroke
				(width 0.1)
				(type default)
			)
			(layer "B.Fab")
		)
		(fp_line
			(start -0.4953 1.6002)
			(end 0.4953 1.6002)
			(stroke
				(width 0.1)
				(type default)
			)
			(layer "B.Fab")
		)
		(fp_line
			(start -0.4953 -0.2032)
			(end -0.4953 1.6002)
			(stroke
				(width 0.1)
				(type default)
			)
			(layer "B.Fab")
		)
		(pad "1" smd rect
			(at 0 0)
			(size 0.762 0.889)
			(layers "B.Cu" "B.Mask" "B.Paste")
			(net "PVDDQ_DEF")
		)
		(pad "2" smd rect
			(at 0 1.397)
			(size 0.762 0.889)
			(layers "B.Cu" "B.Mask" "B.Paste")
			(net "GND")
		)
		(zone
			(layer "B.Cu")
			(hatch none 0.5)
			(connect_pads
				(clearance 0)
			)
			(min_thickness 0.25)
			(keepout
				(tracks not_allowed)
				(vias allowed)
				(pads allowed)
				(copperpour not_allowed)
				(footprints allowed)
			)
			(placement
				(enabled no)
				(sheetname "")
			)
			(fill
				(thermal_gap 0.5)
				(thermal_bridge_width 0.5)
				(island_removal_mode 0)
			)
			(polygon
				(pts
					(xy 331.724 -156.2735) (xy 331.724 -156.7815) (xy 330.962 -156.7815) (xy 330.962 -156.2735)
				)
			)
		)
		(zone
			(layer "B.Cu")
			(hatch none 0.5)
			(connect_pads
				(clearance 0)
			)
			(min_thickness 0.25)
			(keepout
				(tracks allowed)
				(vias not_allowed)
				(pads allowed)
				(copperpour not_allowed)
				(footprints allowed)
			)
			(placement
				(enabled no)
				(sheetname "")
			)
			(fill
				(thermal_gap 0.5)
				(thermal_bridge_width 0.5)
				(island_removal_mode 0)
			)
			(polygon
				(pts
					(xy 331.724 -156.2735) (xy 331.724 -156.7815) (xy 330.962 -156.7815) (xy 330.962 -156.2735)
				)
			)
		)
	)
)
